# S9S_MB_2U (Grand Teton) — schematic netlist excerpt (pin names and nets, part order shuffled) for the footprints in the layout excerpt that follows; sources: Cadence DE-HDL packaged netlist, KiCad conversion of 03242023_DA0F0TMBIJ0_F0T_Motherboard_J_brd_V01_OCP.brd

PR1339  Q_RES  9.76K 1% CHIP  pkg 0402LF  page 299 : A = PVPP_HBM_CPU1_CS ; B = GND
D72  Q_LED  IC  pkg SMLF  page 256 : A = LED_RST_PLD_CPU1_DRAM_GH_N ; C = LED_RST_PLD_CPU1_DRAM_GH_N_D

(kicad_pcb
	(version 20260206)
	(generator "pcbnew")
	(generator_version "10.0")
	(general
		(thickness 1.6)
		(legacy_teardrops no)
	)
	(paper "A4")
	(title_block
		(title "03242023_DA0F0TMBIJ0_F0T_Motherboard_J_brd_V01_OCP.brd")
		(comment 1 "Grand Teton / footprints 648-649 of 6105")
	)
	(layers
		(0 "F.Cu" signal "TOP")
		(4 "In1.Cu" signal "GND")
		(6 "In2.Cu" signal "IN1")
		(8 "In3.Cu" signal "GND1")
		(10 "In4.Cu" signal "IN2")
		(12 "In5.Cu" signal "GND2")
		(14 "In6.Cu" signal "IN3")
		(16 "In7.Cu" signal "GND3")
		(18 "In8.Cu" signal "VCC")
		(20 "In9.Cu" signal "VCC1")
		(22 "In10.Cu" signal "GND4")
		(24 "In11.Cu" signal "IN4")
		(26 "In12.Cu" signal "GND5")
		(28 "In13.Cu" signal "IN5")
		(30 "In14.Cu" signal "GND6")
		(32 "In15.Cu" signal "IN6")
		(34 "In16.Cu" signal "GND7")
		(2 "B.Cu" signal "BOTTOM")
		(9 "F.Adhes" user "F.Adhesive")
		(11 "B.Adhes" user "B.Adhesive")
		(13 "F.Paste" user "Package Geometry/Pastemask Top")
		(15 "B.Paste" user "Package Geometry/Pastemask Bottom")
		(5 "F.SilkS" user "Ref Des/Silkscreen Top")
		(7 "B.SilkS" user "Ref Des/Silkscreen Bottom")
		(1 "F.Mask" user "Board Geometry/Soldermask Top")
		(3 "B.Mask" user "Board Geometry/Soldermask Bottom")
		(17 "Dwgs.User" user "User.Drawings")
		(19 "Cmts.User" user "User.Comments")
		(21 "Eco1.User" user "User.Eco1")
		(23 "Eco2.User" user "User.Eco2")
		(25 "Edge.Cuts" user "Board Geometry/Outline")
		(27 "Margin" user)
		(31 "F.CrtYd" user "Package Geometry/Place Bound Top")
		(29 "B.CrtYd" user "Package Geometry/Place Bound Bottom")
		(35 "F.Fab" user "Ref Des/Assembly Top")
		(33 "B.Fab" user "Ref Des/Assembly Bottom")
	)
	(footprint ""
		(layer "F.Cu")
		(at 58.578496 -70.78599)
		(property "Reference" "D72"
			(at -31.785306 50.178462 90)
			(unlocked yes)
			(layer "F.SilkS")
			(effects
				(font
					(size 0.635 0.4064)
					(thickness 0.1524)
				)
				(justify left)
			)
		)
		(property "Value" ""
			(at 0 0 0)
			(layer "F.Fab")
			(effects
				(font
					(size 1.27 1.27)
				)
			)
		)
		(duplicate_pad_numbers_are_jumpers no)
		(fp_line
			(start -0.90678 0.4826)
			(end -0.90678 -0.4699)
			(stroke
				(width 0.1524)
				(type default)
			)
			(layer "F.SilkS")
		)
		(fp_line
			(start -0.89408 -0.4826)
			(end 0.90678 -0.4826)
			(stroke
				(width 0.1524)
				(type default)
			)
			(layer "F.SilkS")
		)
		(fp_line
			(start -0.79248 -0.4826)
			(end 1.03378 -0.4826)
			(stroke
				(width 0.1524)
				(type default)
			)
			(layer "F.SilkS")
		)
		(fp_line
			(start -0.64008 -0.4826)
			(end 1.16078 -0.4826)
			(stroke
				(width 0.1524)
				(type default)
			)
			(layer "F.SilkS")
		)
		(fp_line
			(start 0.90678 -0.4826)
			(end 0.90678 0.4826)
			(stroke
				(width 0.1524)
				(type default)
			)
			(layer "F.SilkS")
		)
		(fp_line
			(start 0.90678 0.4826)
			(end -0.90678 0.4826)
			(stroke
				(width 0.1524)
				(type default)
			)
			(layer "F.SilkS")
		)
		(fp_line
			(start 1.03378 -0.4826)
			(end 1.03378 0.4826)
			(stroke
				(width 0.1524)
				(type default)
			)
			(layer "F.SilkS")
		)
		(fp_line
			(start 1.03378 0.4826)
			(end -0.79248 0.4826)
			(stroke
				(width 0.1524)
				(type default)
			)
			(layer "F.SilkS")
		)
		(fp_line
			(start 1.16078 -0.4826)
			(end 1.16078 0.4826)
			(stroke
				(width 0.1524)
				(type default)
			)
			(layer "F.SilkS")
		)
		(fp_line
			(start 1.16078 0.4826)
			(end -0.64008 0.4826)
			(stroke
				(width 0.1524)
				(type default)
			)
			(layer "F.SilkS")
		)
		(fp_line
			(start -0.499872 -0.249936)
			(end 0.499872 -0.249936)
			(stroke
				(width 0.1)
				(type default)
			)
			(layer "F.Fab")
		)
		(fp_line
			(start -0.499872 0.249936)
			(end -0.499872 -0.249936)
			(stroke
				(width 0.1)
				(type default)
			)
			(layer "F.Fab")
		)
		(fp_line
			(start 0.499872 -0.249936)
			(end 0.499872 0.249936)
			(stroke
				(width 0.1)
				(type default)
			)
			(layer "F.Fab")
		)
		(fp_line
			(start 0.499872 0.249936)
			(end -0.499872 0.249936)
			(stroke
				(width 0.1)
				(type default)
			)
			(layer "F.Fab")
		)
		(pad "A" smd rect
			(at -0.47498 0)
			(size 0.6096 0.7112)
			(layers "F.Cu" "F.Mask" "F.Paste")
			(net "LED_RST_PLD_CPU1_DRAM_GH_N")
		)
		(pad "C" smd rect
			(at 0.47498 0)
			(size 0.6096 0.7112)
			(layers "F.Cu" "F.Mask" "F.Paste")
			(net "LED_RST_PLD_CPU1_DRAM_GH_N_D")
		)
	)
	(footprint ""
		(layer "F.Cu")
		(at 121.984008 -360.043222 90)
		(property "Reference" "PR1339"
			(at 0 0 90)
			(layer "F.SilkS")
			(hide yes)
			(effects
				(font
					(size 1.27 1.27)
				)
			)
		)
		(property "Value" ""
			(at 0 0 90)
			(layer "F.Fab")
			(effects
				(font
					(size 1.27 1.27)
				)
			)
		)
		(duplicate_pad_numbers_are_jumpers no)
		(fp_line
			(start 0.7874 -0.4064)
			(end 0.7874 0.4064)
			(stroke
				(width 0.1524)
				(type default)
			)
			(layer "F.SilkS")
		)
		(fp_line
			(start -0.7874 -0.4064)
			(end 0.7874 -0.4064)
			(stroke
				(width 0.1524)
				(type default)
			)
			(layer "F.SilkS")
		)
		(fp_line
			(start 0.7874 0.4064)
			(end -0.7874 0.4064)
			(stroke
				(width 0.1524)
				(type default)
			)
			(layer "F.SilkS")
		)
		(fp_line
			(start -0.7874 0.4064)
			(end -0.7874 -0.4064)
			(stroke
				(width 0.1524)
				(type default)
			)
			(layer "F.SilkS")
		)
		(fp_line
			(start -0.12065 -0.305054)
			(end -0.12065 -0.2794)
			(stroke
				(width 0.1)
				(type default)
			)
			(layer "F.Fab")
		)
		(fp_line
			(start -0.67945 -0.305054)
			(end -0.12065 -0.305054)
			(stroke
				(width 0.1)
				(type default)
			)
			(layer "F.Fab")
		)
		(fp_line
			(start 0.67945 -0.3048)
			(end 0.67945 0.3048)
			(stroke
				(width 0.1)
				(type default)
			)
			(layer "F.Fab")
		)
		(fp_line
			(start 0.12065 -0.3048)
			(end 0.67945 -0.3048)
			(stroke
				(width 0.1)
				(type default)
			)
			(layer "F.Fab")
		)
		(fp_line
			(start 0.12065 -0.2794)
			(end 0.12065 -0.3048)
			(stroke
				(width 0.1)
				(type default)
			)
			(layer "F.Fab")
		)
		(fp_line
			(start -0.12065 -0.2794)
			(end 0.12065 -0.2794)
			(stroke
				(width 0.1)
				(type default)
			)
			(layer "F.Fab")
		)
		(fp_line
			(start 0.120396 0.2794)
			(end -0.12065 0.2794)
			(stroke
				(width 0.1)
				(type default)
			)
			(layer "F.Fab")
		)
		(fp_line
			(start -0.12065 0.2794)
			(end -0.12065 0.3048)
			(stroke
				(width 0.1)
				(type default)
			)
			(layer "F.Fab")
		)
		(fp_line
			(start 0.67945 0.3048)
			(end 0.120396 0.3048)
			(stroke
				(width 0.1)
				(type default)
			)
			(layer "F.Fab")
		)
		(fp_line
			(start 0.120396 0.3048)
			(end 0.120396 0.2794)
			(stroke
				(width 0.1)
				(type default)
			)
			(layer "F.Fab")
		)
		(fp_line
			(start -0.12065 0.3048)
			(end -0.67945 0.3048)
			(stroke
				(width 0.1)
				(type default)
			)
			(layer "F.Fab")
		)
		(fp_line
			(start -0.67945 0.3048)
			(end -0.67945 -0.305054)
			(stroke
				(width 0.1)
				(type default)
			)
			(layer "F.Fab")
		)
		(pad "1" smd circle
			(at -0.40005 0 90)
			(size 0 0)
			(layers "F.Cu" "F.Mask" "F.Paste")
			(net "PVPP_HBM_CPU1_CS")
		)
		(pad "2" smd circle
			(at 0.40005 0 90)
			(size 0 0)
			(layers "F.Cu" "F.Mask" "F.Paste")
			(net "GND")
		)
	)
)
